(kicad_pcb
	(version 20241229)
	(generator "pcbnew")
	(generator_version "9.0")
	(general
		(thickness 1.294)
		(legacy_teardrops no)
	)
	(paper "A3")
	(title_block
		(title "Kintex 410T devboard")
		(date "2024-04-03")
		(rev "1.1.2")
		(comment 9 "footprints 847-852 of 975")
	)
	(layers
		(0 "F.Cu" mixed)
		(4 "In1.Cu" power)
		(6 "In2.Cu" power)
		(8 "In3.Cu" mixed)
		(10 "In4.Cu" power)
		(12 "In5.Cu" mixed)
		(14 "In6.Cu" power)
		(16 "In7.Cu" mixed)
		(18 "In8.Cu" power)
		(2 "B.Cu" mixed)
		(9 "F.Adhes" user "F.Adhesive")
		(11 "B.Adhes" user "B.Adhesive")
		(13 "F.Paste" user)
		(15 "B.Paste" user)
		(5 "F.SilkS" user "F.Silkscreen")
		(7 "B.SilkS" user "B.Silkscreen")
		(1 "F.Mask" user)
		(3 "B.Mask" user)
		(17 "Dwgs.User" user "User.Drawings")
		(19 "Cmts.User" user "User.Comments")
		(21 "Eco1.User" user "User.Eco1")
		(23 "Eco2.User" user "User.Eco2")
		(25 "Edge.Cuts" user)
		(27 "Margin" user)
		(31 "F.CrtYd" user "F.Courtyard")
		(29 "B.CrtYd" user "B.Courtyard")
		(35 "F.Fab" user)
		(33 "B.Fab" user)
	)
	(footprint "antmicro-footprints:NetTie-2_SMD_Pad0.127mm"
		(layer "B.Cu")
		(at 196.92 87.08 45)
		(descr "Net tie, 2 pin, 0.127mm  SMD pads")
		(tags "net tie")
		(property "Reference" "NT38"
			(at -0.128 1.345 225)
			(layer "B.SilkS")
			(hide yes)
			(effects
				(font
					(size 0.7 0.7)
					(thickness 0.15)
				)
				(justify left bottom mirror)
			)
		)
		(property "Value" "Net-Tie_2"
			(at 0 -1.199 225)
			(layer "B.Fab")
			(effects
				(font
					(size 0.7 0.7)
					(thickness 0.15)
				)
				(justify left bottom mirror)
			)
		)
		(property "Description" "Net tie, 2 pins"
			(at 0 0 45)
			(layer "F.Fab")
			(hide yes)
			(effects
				(font
					(size 1.27 1.27)
					(thickness 0.15)
				)
			)
		)
		(property "Author" "Antmicro"
			(at 119.251391 -113.738326 0)
			(layer "B.Fab")
			(hide yes)
			(effects
				(font
					(size 1 1)
					(thickness 0.15)
				)
				(justify mirror)
			)
		)
		(property "License" "Apache-2.0"
			(at 119.251391 -113.738326 0)
			(layer "B.Fab")
			(hide yes)
			(effects
				(font
					(size 1 1)
					(thickness 0.15)
				)
				(justify mirror)
			)
		)
		(property "MPN" ""
			(at 119.251391 -113.738326 0)
			(layer "B.Fab")
			(hide yes)
			(effects
				(font
					(size 1 1)
					(thickness 0.15)
				)
				(justify mirror)
			)
		)
		(property "Manufacturer" ""
			(at 119.251391 -113.738326 0)
			(layer "B.Fab")
			(hide yes)
			(effects
				(font
					(size 1 1)
					(thickness 0.15)
				)
				(justify mirror)
			)
		)
		(sheetname "DC-DC Converters")
		(sheetfile "dc-dc.kicad_sch")
		(attr exclude_from_pos_files)
		(net_tie_pad_groups "1, 2")
		(fp_poly
			(pts
				(xy -0.0635 0.0635) (xy 0.0625 0.0635) (xy 0.0625 -0.0635) (xy -0.0635 -0.0635)
			)
			(stroke
				(width 0)
				(type solid)
			)
			(fill yes)
			(layer "B.Cu")
		)
		(pad "1" smd roundrect
			(at -0.127001 0 225)
			(size 0.127 0.127)
			(layers "B.Cu")
			(roundrect_rratio 0.5)
			(chamfer_ratio 0)
			(chamfer top_left bottom_left)
			(net 1226 "/DC-DC Converters/SENSE_1V2_P")
			(pinfunction "1")
			(pintype "passive")
		)
		(pad "2" smd roundrect
			(at 0.125999 0 45)
			(size 0.127 0.127)
			(layers "B.Cu")
			(roundrect_rratio 0.5)
			(chamfer_ratio 0)
			(chamfer top_left bottom_left)
			(net 727 "+1V2")
			(pinfunction "2")
			(pintype "passive")
		)
	)
	(footprint "antmicro-footprints:R_0402_1005Metric"
		(layer "B.Cu")
		(at 255.001 161.6 90)
		(descr "Resistor SMD 0402")
		(tags "resistor SMD 0402")
		(property "Reference" "R245"
			(at 1.35 5.299 270)
			(layer "B.SilkS")
			(effects
				(font
					(size 0.7 0.7)
					(thickness 0.15)
				)
				(justify left bottom mirror)
			)
		)
		(property "Value" "R_49R9_0402"
			(at 0 -1.4 270)
			(layer "B.Fab")
			(effects
				(font
					(size 0.7 0.7)
					(thickness 0.15)
				)
				(justify left bottom mirror)
			)
		)
		(property "Description" "SMD Chip Resistor, 49.9 ohm, ± 1%, 62.5 mW, 0402 [1005 Metric], Thick Film, General Purpose"
			(at 0 0 90)
			(layer "F.Fab")
			(hide yes)
			(effects
				(font
					(size 1.27 1.27)
					(thickness 0.15)
				)
			)
		)
		(property "Author" "Antmicro"
			(at 416.601 -93.401 0)
			(layer "B.Fab")
			(hide yes)
			(effects
				(font
					(size 1 1)
					(thickness 0.15)
				)
				(justify mirror)
			)
		)
		(property "License" "Apache-2.0"
			(at 416.601 -93.401 0)
			(layer "B.Fab")
			(hide yes)
			(effects
				(font
					(size 1 1)
					(thickness 0.15)
				)
				(justify mirror)
			)
		)
		(property "MPN" "CR0402-FX-49R9GLF"
			(at 416.601 -93.401 0)
			(layer "B.Fab")
			(hide yes)
			(effects
				(font
					(size 1 1)
					(thickness 0.15)
				)
				(justify mirror)
			)
		)
		(property "Manufacturer" "Bourns"
			(at 416.601 -93.401 0)
			(layer "B.Fab")
			(hide yes)
			(effects
				(font
					(size 1 1)
					(thickness 0.15)
				)
				(justify mirror)
			)
		)
		(property "Tolerance" "1%"
			(at 416.601 -93.401 0)
			(layer "B.Fab")
			(hide yes)
			(effects
				(font
					(size 1 1)
					(thickness 0.15)
				)
				(justify mirror)
			)
		)
		(property "Val" "49R9"
			(at 416.601 -93.401 0)
			(layer "B.Fab")
			(hide yes)
			(effects
				(font
					(size 1 1)
					(thickness 0.15)
				)
				(justify mirror)
			)
		)
		(sheetname "HDMI + Ethernet")
		(sheetfile "hdmi-ethernet.kicad_sch")
		(attr smd)
		(fp_rect
			(start -0.925 0.47)
			(end 0.925 -0.47)
			(stroke
				(width 0.05)
				(type default)
			)
			(fill no)
			(layer "B.CrtYd")
		)
		(fp_rect
			(start -0.5 0.25)
			(end 0.5 -0.25)
			(stroke
				(width 0.15)
				(type solid)
			)
			(fill no)
			(layer "B.Fab")
		)
		(pad "1" smd roundrect
			(at -0.48 0 90)
			(size 0.59 0.64)
			(layers "B.Cu" "B.Mask" "B.Paste")
			(roundrect_rratio 0.25)
			(net 724 "/HDMI + Ethernet/ETH1_P")
			(pintype "passive")
		)
		(pad "2" smd roundrect
			(at 0.48 0 90)
			(size 0.59 0.64)
			(layers "B.Cu" "B.Mask" "B.Paste")
			(roundrect_rratio 0.25)
			(net 721 "/HDMI + Ethernet/ETH_3V3")
			(pintype "passive")
		)
	)
	(footprint "antmicro-footprints:R_0402_1005Metric"
		(layer "B.Cu")
		(at 165.685001 118.065001 180)
		(descr "Resistor SMD 0402")
		(tags "resistor SMD 0402")
		(property "Reference" "R267"
			(at 0.835001 -0.434999 0)
			(layer "B.SilkS")
			(effects
				(font
					(size 0.7 0.7)
					(thickness 0.15)
				)
				(justify left bottom mirror)
			)
		)
		(property "Value" "R_4k7_0402"
			(at 0 -1.4 0)
			(layer "B.Fab")
			(effects
				(font
					(size 0.7 0.7)
					(thickness 0.15)
				)
				(justify left bottom mirror)
			)
		)
		(property "Description" "SMD Chip Resistor, 4.7 kohm, ± 1%, 62.5 mW, 0402 [1005 Metric], Thick Film, General Purpose"
			(at 0 0 180)
			(layer "F.Fab")
			(hide yes)
			(effects
				(font
					(size 1.27 1.27)
					(thickness 0.15)
				)
			)
		)
		(property "Author" "Antmicro"
			(at 331.370002 236.130002 0)
			(layer "B.Fab")
			(hide yes)
			(effects
				(font
					(size 1 1)
					(thickness 0.15)
				)
				(justify mirror)
			)
		)
		(property "License" "Apache-2.0"
			(at 331.370002 236.130002 0)
			(layer "B.Fab")
			(hide yes)
			(effects
				(font
					(size 1 1)
					(thickness 0.15)
				)
				(justify mirror)
			)
		)
		(property "MPN" "CR0402-FX-4701GLF"
			(at 331.370002 236.130002 0)
			(layer "B.Fab")
			(hide yes)
			(effects
				(font
					(size 1 1)
					(thickness 0.15)
				)
				(justify mirror)
			)
		)
		(property "Manufacturer" "Bourns"
			(at 331.370002 236.130002 0)
			(layer "B.Fab")
			(hide yes)
			(effects
				(font
					(size 1 1)
					(thickness 0.15)
				)
				(justify mirror)
			)
		)
		(property "Tolerance" "1%"
			(at 331.370002 236.130002 0)
			(layer "B.Fab")
			(hide yes)
			(effects
				(font
					(size 1 1)
					(thickness 0.15)
				)
				(justify mirror)
			)
		)
		(property "Val" "4k7"
			(at 331.370002 236.130002 0)
			(layer "B.Fab")
			(hide yes)
			(effects
				(font
					(size 1 1)
					(thickness 0.15)
				)
				(justify mirror)
			)
		)
		(sheetname "FMC+ HSPC")
		(sheetfile "fmc-hspc.kicad_sch")
		(attr smd)
		(fp_rect
			(start -0.925 0.47)
			(end 0.925 -0.47)
			(stroke
				(width 0.05)
				(type default)
			)
			(fill no)
			(layer "B.CrtYd")
		)
		(fp_rect
			(start -0.5 0.25)
			(end 0.5 -0.25)
			(stroke
				(width 0.15)
				(type solid)
			)
			(fill no)
			(layer "B.Fab")
		)
		(pad "1" smd roundrect
			(at -0.48 0 180)
			(size 0.59 0.64)
			(layers "B.Cu" "B.Mask" "B.Paste")
			(roundrect_rratio 0.25)
			(net 24 "+3V3")
			(pintype "passive")
		)
		(pad "2" smd roundrect
			(at 0.48 0 180)
			(size 0.59 0.64)
			(layers "B.Cu" "B.Mask" "B.Paste")
			(roundrect_rratio 0.25)
			(net 383 "FMC.SCL_3V3")
			(pintype "passive")
		)
	)
	(footprint "antmicro-footprints:R_0402_1005Metric"
		(layer "B.Cu")
		(at 195.691252 95.85 180)
		(descr "Resistor SMD 0402")
		(tags "resistor SMD 0402")
		(property "Reference" "R207"
			(at 0.716252 -0.425 0)
			(layer "B.SilkS")
			(effects
				(font
					(size 0.7 0.7)
					(thickness 0.15)
				)
				(justify left bottom mirror)
			)
		)
		(property "Value" "R_10k_0402"
			(at 0 -1.4 0)
			(layer "B.Fab")
			(effects
				(font
					(size 0.7 0.7)
					(thickness 0.15)
				)
				(justify left bottom mirror)
			)
		)
		(property "Description" "SMD Chip Resistor, 10 kohm, ± 1%, 62.5 mW, 0402 [1005 Metric], Thick Film, General Purpose"
			(at 0 0 180)
			(layer "F.Fab")
			(hide yes)
			(effects
				(font
					(size 1.27 1.27)
					(thickness 0.15)
				)
			)
		)
		(property "Author" "Antmicro"
			(at 391.382504 191.7 0)
			(layer "B.Fab")
			(hide yes)
			(effects
				(font
					(size 1 1)
					(thickness 0.15)
				)
				(justify mirror)
			)
		)
		(property "DNP" "DNP"
			(at 391.382504 191.7 0)
			(layer "B.Fab")
			(hide yes)
			(effects
				(font
					(size 1 1)
					(thickness 0.15)
				)
				(justify mirror)
			)
		)
		(property "License" "Apache-2.0"
			(at 391.382504 191.7 0)
			(layer "B.Fab")
			(hide yes)
			(effects
				(font
					(size 1 1)
					(thickness 0.15)
				)
				(justify mirror)
			)
		)
		(property "MPN" "CR0402-FX-1002GLF"
			(at 391.382504 191.7 0)
			(layer "B.Fab")
			(hide yes)
			(effects
				(font
					(size 1 1)
					(thickness 0.15)
				)
				(justify mirror)
			)
		)
		(property "Manufacturer" "Bourns"
			(at 391.382504 191.7 0)
			(layer "B.Fab")
			(hide yes)
			(effects
				(font
					(size 1 1)
					(thickness 0.15)
				)
				(justify mirror)
			)
		)
		(property "Tolerance" "1%"
			(at 391.382504 191.7 0)
			(layer "B.Fab")
			(hide yes)
			(effects
				(font
					(size 1 1)
					(thickness 0.15)
				)
				(justify mirror)
			)
		)
		(property "Val" "10k"
			(at 391.382504 191.7 0)
			(layer "B.Fab")
			(hide yes)
			(effects
				(font
					(size 1 1)
					(thickness 0.15)
				)
				(justify mirror)
			)
		)
		(property "dnp" ""
			(at 391.382504 191.7 0)
			(layer "B.Fab")
			(hide yes)
			(effects
				(font
					(size 1 1)
					(thickness 0.15)
				)
				(justify mirror)
			)
		)
		(property "exclude_from_bom" ""
			(at 391.382504 191.7 0)
			(layer "B.Fab")
			(hide yes)
			(effects
				(font
					(size 1 1)
					(thickness 0.15)
				)
				(justify mirror)
			)
		)
		(sheetname "HDMI + Ethernet")
		(sheetfile "hdmi-ethernet.kicad_sch")
		(attr smd exclude_from_bom)
		(fp_rect
			(start -0.925 0.47)
			(end 0.925 -0.47)
			(stroke
				(width 0.05)
				(type default)
			)
			(fill no)
			(layer "B.CrtYd")
		)
		(fp_rect
			(start -0.5 0.25)
			(end 0.5 -0.25)
			(stroke
				(width 0.15)
				(type solid)
			)
			(fill no)
			(layer "B.Fab")
		)
		(pad "1" smd roundrect
			(at -0.48 0 180)
			(size 0.59 0.64)
			(layers "B.Cu" "B.Mask" "B.Paste")
			(roundrect_rratio 0.25)
			(net 509 "/FPGA Bank 16 & 17/GBE_RGMII.RX_DV")
			(pintype "passive")
		)
		(pad "2" smd roundrect
			(at 0.48 0 180)
			(size 0.59 0.64)
			(layers "B.Cu" "B.Mask" "B.Paste")
			(roundrect_rratio 0.25)
			(net 24 "+3V3")
			(pintype "passive")
		)
	)
	(footprint "antmicro-footprints:C_0402_1005Metric"
		(layer "B.Cu")
		(at 214.5 135 -90)
		(descr "Capacitor SMD 0402")
		(tags "capacitor SMD 0402")
		(property "Reference" "C41"
			(at -1.05 -1.325 90)
			(layer "B.SilkS")
			(effects
				(font
					(size 0.7 0.7)
					(thickness 0.15)
				)
				(justify left bottom mirror)
			)
		)
		(property "Value" "C_100n_0402"
			(at 0 -1.169 90)
			(layer "B.Fab")
			(effects
				(font
					(size 0.7 0.7)
					(thickness 0.15)
				)
				(justify left bottom mirror)
			)
		)
		(property "Description" "SMD Multilayer Ceramic Capacitor, 0.1 µF, 50 V, 0402 [1005 Metric], ± 10%, X5R, GRM Series"
			(at 0 0 270)
			(layer "F.Fab")
			(hide yes)
			(effects
				(font
					(size 1.27 1.27)
					(thickness 0.15)
				)
			)
		)
		(property "Author" "Antmicro"
			(at 79.5 349.5 0)
			(layer "B.Fab")
			(hide yes)
			(effects
				(font
					(size 1 1)
					(thickness 0.15)
				)
				(justify mirror)
			)
		)
		(property "Dielectric" "X5R"
			(at 79.5 349.5 0)
			(layer "B.Fab")
			(hide yes)
			(effects
				(font
					(size 1 1)
					(thickness 0.15)
				)
				(justify mirror)
			)
		)
		(property "License" "Apache-2.0"
			(at 79.5 349.5 0)
			(layer "B.Fab")
			(hide yes)
			(effects
				(font
					(size 1 1)
					(thickness 0.15)
				)
				(justify mirror)
			)
		)
		(property "MPN" "GRM155R61H104KE14D"
			(at 79.5 349.5 0)
			(layer "B.Fab")
			(hide yes)
			(effects
				(font
					(size 1 1)
					(thickness 0.15)
				)
				(justify mirror)
			)
		)
		(property "Manufacturer" "Murata"
			(at 79.5 349.5 0)
			(layer "B.Fab")
			(hide yes)
			(effects
				(font
					(size 1 1)
					(thickness 0.15)
				)
				(justify mirror)
			)
		)
		(property "Val" "100n"
			(at 79.5 349.5 0)
			(layer "B.Fab")
			(hide yes)
			(effects
				(font
					(size 1 1)
					(thickness 0.15)
				)
				(justify mirror)
			)
		)
		(property "Voltage" "50V"
			(at 79.5 349.5 0)
			(layer "B.Fab")
			(hide yes)
			(effects
				(font
					(size 1 1)
					(thickness 0.15)
				)
				(justify mirror)
			)
		)
		(sheetname "FPGA Bank 12 & 13")
		(sheetfile "fpga-bank-12-13.kicad_sch")
		(attr smd)
		(fp_rect
			(start -0.925 0.47)
			(end 0.925 -0.47)
			(stroke
				(width 0.05)
				(type default)
			)
			(fill no)
			(layer "B.CrtYd")
		)
		(fp_line
			(start -0.494 0.25)
			(end 0.504 0.25)
			(stroke
				(width 0.15)
				(type solid)
			)
			(layer "B.Fab")
		)
		(fp_line
			(start 0.504 0.25)
			(end 0.504 -0.248)
			(stroke
				(width 0.15)
				(type solid)
			)
			(layer "B.Fab")
		)
		(fp_line
			(start -0.494 -0.248)
			(end -0.494 0.25)
			(stroke
				(width 0.15)
				(type solid)
			)
			(layer "B.Fab")
		)
		(fp_line
			(start 0.504 -0.248)
			(end -0.494 -0.248)
			(stroke
				(width 0.15)
				(type solid)
			)
			(layer "B.Fab")
		)
		(pad "1" smd roundrect
			(at -0.48 0 270)
			(size 0.59 0.64)
			(layers "B.Cu" "B.Mask" "B.Paste")
			(roundrect_rratio 0.25)
			(net 1 "GND")
			(pintype "passive")
		)
		(pad "2" smd roundrect
			(at 0.48 0 270)
			(size 0.59 0.64)
			(layers "B.Cu" "B.Mask" "B.Paste")
			(roundrect_rratio 0.25)
			(net 24 "+3V3")
			(pintype "passive")
		)
	)
	(footprint "antmicro-footprints:C_0402_1005Metric"
		(layer "B.Cu")
		(at 203 135.5)
		(descr "Capacitor SMD 0402")
		(tags "capacitor SMD 0402")
		(property "Reference" "C77"
			(at 28.9 -28.075 180)
			(layer "B.SilkS")
			(effects
				(font
					(size 0.7 0.7)
					(thickness 0.15)
				)
				(justify left bottom mirror)
			)
		)
		(property "Value" "C_100n_0402"
			(at 0 -1.169 180)
			(layer "B.Fab")
			(effects
				(font
					(size 0.7 0.7)
					(thickness 0.15)
				)
				(justify left bottom mirror)
			)
		)
		(property "Description" "SMD Multilayer Ceramic Capacitor, 0.1 µF, 50 V, 0402 [1005 Metric], ± 10%, X5R, GRM Series"
			(at 0 0 0)
			(layer "F.Fab")
			(hide yes)
			(effects
				(font
					(size 1.27 1.27)
					(thickness 0.15)
				)
			)
		)
		(property "Author" "Antmicro"
			(at 0 0 0)
			(layer "B.Fab")
			(hide yes)
			(effects
				(font
					(size 1 1)
					(thickness 0.15)
				)
				(justify mirror)
			)
		)
		(property "Dielectric" "X5R"
			(at 0 0 0)
			(layer "B.Fab")
			(hide yes)
			(effects
				(font
					(size 1 1)
					(thickness 0.15)
				)
				(justify mirror)
			)
		)
		(property "License" "Apache-2.0"
			(at 0 0 0)
			(layer "B.Fab")
			(hide yes)
			(effects
				(font
					(size 1 1)
					(thickness 0.15)
				)
				(justify mirror)
			)
		)
		(property "MPN" "GRM155R61H104KE14D"
			(at 0 0 0)
			(layer "B.Fab")
			(hide yes)
			(effects
				(font
					(size 1 1)
					(thickness 0.15)
				)
				(justify mirror)
			)
		)
		(property "Manufacturer" "Murata"
			(at 0 0 0)
			(layer "B.Fab")
			(hide yes)
			(effects
				(font
					(size 1 1)
					(thickness 0.15)
				)
				(justify mirror)
			)
		)
		(property "Val" "100n"
			(at 0 0 0)
			(layer "B.Fab")
			(hide yes)
			(effects
				(font
					(size 1 1)
					(thickness 0.15)
				)
				(justify mirror)
			)
		)
		(property "Voltage" "50V"
			(at 0 0 0)
			(layer "B.Fab")
			(hide yes)
			(effects
				(font
					(size 1 1)
					(thickness 0.15)
				)
				(justify mirror)
			)
		)
		(sheetname "FPGA Bank 18 & 32")
		(sheetfile "fpga-bank-18-32.kicad_sch")
		(attr smd)
		(fp_rect
			(start -0.925 0.47)
			(end 0.925 -0.47)
			(stroke
				(width 0.05)
				(type default)
			)
			(fill no)
			(layer "B.CrtYd")
		)
		(fp_line
			(start -0.494 -0.248)
			(end -0.494 0.25)
			(stroke
				(width 0.15)
				(type solid)
			)
			(layer "B.Fab")
		)
		(fp_line
			(start -0.494 0.25)
			(end 0.504 0.25)
			(stroke
				(width 0.15)
				(type solid)
			)
			(layer "B.Fab")
		)
		(fp_line
			(start 0.504 -0.248)
			(end -0.494 -0.248)
			(stroke
				(width 0.15)
				(type solid)
			)
			(layer "B.Fab")
		)
		(fp_line
			(start 0.504 0.25)
			(end 0.504 -0.248)
			(stroke
				(width 0.15)
				(type solid)
			)
			(layer "B.Fab")
		)
		(pad "1" smd roundrect
			(at -0.48 0)
			(size 0.59 0.64)
			(layers "B.Cu" "B.Mask" "B.Paste")
			(roundrect_rratio 0.25)
			(net 1 "GND")
			(pintype "passive")
		)
		(pad "2" smd roundrect
			(at 0.48 0)
			(size 0.59 0.64)
			(layers "B.Cu" "B.Mask" "B.Paste")
			(roundrect_rratio 0.25)
			(net 26 "+1V8")
			(pintype "passive")
		)
	)
)
